#ISCELL
  mstr_misc dns *
  *
#ISCELL
  mstr_symbols bom_note *
  *
#ISCELL
  mstr_symbols cad_note *
  *
#ISCELL
  mstr_symbols intel_corp_bpage *
  *
#ISCELL
  mstr_symbols p3v3_stby *
  page162_i10
#CELL
  mstr_discrete res *
  page162_i13
#ISCELL
  mstr_standard offpage *
  page162_i16
#ISCELL
  mstr_standard offpage *
  page162_i17
#ISCELL
  mstr_standard offpage *
  page162_i19
#ISCELL
  mstr_standard offpage *
  page162_i21
#CELL
  mstr_discrete res *
  page162_i22
#CELL
  mstr_discrete res *
  page162_i24
#CELL
  dev_discrete cap_a *
  page162_i28
#CELL
  dev_discrete cap_a *
  page162_i30
#ISCELL
  mstr_symbols gnd *
  page162_i31
#CELL
  mstr_memory w25q128 *
  page162_i32
#ISCELL
  mstr_symbols gnd *
  page162_i33
#CELL
  mstr_discrete res *
  page162_i35
#ISCELL
  mstr_symbols gnd *
  page162_i6
#CELL
  mstr_discrete res *
  page162_i8
#CELL
  mstr_discrete res *
  page162_i9
